# T6G (Grand Teton) — schematic netlist excerpt (pin names and nets, part order shuffled) for the footprints in the layout excerpt that follows; sources: Cadence DE-HDL packaged netlist, KiCad conversion of 04192023_DAF0TMB3IC0_F0TG_MB_C_brd_V02_OCP.brd

C1511  Q_CAP  33PF 50V 5% NPO  pkg 0402  page 172 : A = JTAG_TRST_N ; B = GND
PC173  Q_CAP  560PF 50V 10% EMPTY  pkg C0402  page 211 : A = SW_PVDDCR_CPU0_P1_SW2 ; B = SW_PVDDCR_CPU0_P1_SW2_RC

(kicad_pcb
	(version 20260206)
	(generator "pcbnew")
	(generator_version "10.0")
	(general
		(thickness 1.6)
		(legacy_teardrops no)
	)
	(paper "A4")
	(title_block
		(title "04192023_DAF0TMB3IC0_F0TG_MB_C_brd_V02_OCP.brd")
		(comment 1 "Grand Teton / footprints 2047-2048 of 8354")
	)
	(layers
		(0 "F.Cu" signal "TOP")
		(4 "In1.Cu" signal "GND")
		(6 "In2.Cu" signal "IN1")
		(8 "In3.Cu" signal "GND1")
		(10 "In4.Cu" signal "IN2")
		(12 "In5.Cu" signal "GND2")
		(14 "In6.Cu" signal "IN3")
		(16 "In7.Cu" signal "GND3")
		(18 "In8.Cu" signal "VCC")
		(20 "In9.Cu" signal "VCC1")
		(22 "In10.Cu" signal "GND4")
		(24 "In11.Cu" signal "IN4")
		(26 "In12.Cu" signal "GND5")
		(28 "In13.Cu" signal "IN5")
		(30 "In14.Cu" signal "GND6")
		(32 "In15.Cu" signal "IN6")
		(34 "In16.Cu" signal "GND7")
		(2 "B.Cu" signal "BOTTOM")
		(9 "F.Adhes" user "F.Adhesive")
		(11 "B.Adhes" user "B.Adhesive")
		(13 "F.Paste" user "Package Geometry/Pastemask Top")
		(15 "B.Paste" user "Package Geometry/Pastemask Bottom")
		(5 "F.SilkS" user "Ref Des/Silkscreen Top")
		(7 "B.SilkS" user "Ref Des/Silkscreen Bottom")
		(1 "F.Mask" user "Board Geometry/Soldermask Top")
		(3 "B.Mask" user "Board Geometry/Soldermask Bottom")
		(17 "Dwgs.User" user "User.Drawings")
		(19 "Cmts.User" user "User.Comments")
		(21 "Eco1.User" user "User.Eco1")
		(23 "Eco2.User" user "User.Eco2")
		(25 "Edge.Cuts" user "Board Geometry/Outline")
		(27 "Margin" user)
		(31 "F.CrtYd" user "Package Geometry/Place Bound Top")
		(29 "B.CrtYd" user "Package Geometry/Place Bound Bottom")
		(35 "F.Fab" user "Ref Des/Assembly Top")
		(33 "B.Fab" user "Ref Des/Assembly Bottom")
	)
	(footprint ""
		(layer "F.Cu")
		(at 94.375732 -185.680096)
		(property "Reference" "PC173"
			(at 0 0 0)
			(layer "F.SilkS")
			(hide yes)
			(effects
				(font
					(size 1.27 1.27)
				)
			)
		)
		(property "Value" ""
			(at 0 0 0)
			(layer "F.Fab")
			(effects
				(font
					(size 1.27 1.27)
				)
			)
		)
		(duplicate_pad_numbers_are_jumpers no)
		(fp_line
			(start -0.7874 -0.4064)
			(end 0.7874 -0.4064)
			(stroke
				(width 0.1524)
				(type default)
			)
			(layer "F.SilkS")
		)
		(fp_line
			(start -0.7874 0.4064)
			(end -0.7874 -0.4064)
			(stroke
				(width 0.1524)
				(type default)
			)
			(layer "F.SilkS")
		)
		(fp_line
			(start 0.7874 -0.4064)
			(end 0.7874 0.4064)
			(stroke
				(width 0.1524)
				(type default)
			)
			(layer "F.SilkS")
		)
		(fp_line
			(start 0.7874 0.4064)
			(end -0.7874 0.4064)
			(stroke
				(width 0.1524)
				(type default)
			)
			(layer "F.SilkS")
		)
		(fp_line
			(start -0.67945 -0.305054)
			(end -0.12065 -0.305054)
			(stroke
				(width 0.1)
				(type default)
			)
			(layer "F.Fab")
		)
		(fp_line
			(start -0.67945 0.3048)
			(end -0.67945 -0.305054)
			(stroke
				(width 0.1)
				(type default)
			)
			(layer "F.Fab")
		)
		(fp_line
			(start -0.12065 -0.305054)
			(end -0.12065 -0.2794)
			(stroke
				(width 0.1)
				(type default)
			)
			(layer "F.Fab")
		)
		(fp_line
			(start -0.12065 -0.2794)
			(end 0.12065 -0.2794)
			(stroke
				(width 0.1)
				(type default)
			)
			(layer "F.Fab")
		)
		(fp_line
			(start -0.12065 0.2794)
			(end -0.12065 0.3048)
			(stroke
				(width 0.1)
				(type default)
			)
			(layer "F.Fab")
		)
		(fp_line
			(start -0.12065 0.3048)
			(end -0.67945 0.3048)
			(stroke
				(width 0.1)
				(type default)
			)
			(layer "F.Fab")
		)
		(fp_line
			(start 0.120396 0.2794)
			(end -0.12065 0.2794)
			(stroke
				(width 0.1)
				(type default)
			)
			(layer "F.Fab")
		)
		(fp_line
			(start 0.120396 0.3048)
			(end 0.120396 0.2794)
			(stroke
				(width 0.1)
				(type default)
			)
			(layer "F.Fab")
		)
		(fp_line
			(start 0.12065 -0.3048)
			(end 0.67945 -0.3048)
			(stroke
				(width 0.1)
				(type default)
			)
			(layer "F.Fab")
		)
		(fp_line
			(start 0.12065 -0.2794)
			(end 0.12065 -0.3048)
			(stroke
				(width 0.1)
				(type default)
			)
			(layer "F.Fab")
		)
		(fp_line
			(start 0.67945 -0.3048)
			(end 0.67945 0.3048)
			(stroke
				(width 0.1)
				(type default)
			)
			(layer "F.Fab")
		)
		(fp_line
			(start 0.67945 0.3048)
			(end 0.120396 0.3048)
			(stroke
				(width 0.1)
				(type default)
			)
			(layer "F.Fab")
		)
		(pad "1" smd circle
			(at -0.40005 0)
			(size 0 0)
			(layers "F.Cu" "F.Mask" "F.Paste")
			(net "SW_PVDDCR_CPU0_P1_SW2")
		)
		(pad "2" smd circle
			(at 0.40005 0)
			(size 0 0)
			(layers "F.Cu" "F.Mask" "F.Paste")
			(net "SW_PVDDCR_CPU0_P1_SW2_RC")
		)
	)
	(footprint ""
		(layer "F.Cu")
		(at 288.26587 -97.967292)
		(property "Reference" "C1511"
			(at 0 0 0)
			(layer "F.SilkS")
			(hide yes)
			(effects
				(font
					(size 1.27 1.27)
				)
			)
		)
		(property "Value" ""
			(at 0 0 0)
			(layer "F.Fab")
			(effects
				(font
					(size 1.27 1.27)
				)
			)
		)
		(duplicate_pad_numbers_are_jumpers no)
		(fp_line
			(start -0.7874 -0.4064)
			(end 0.7874 -0.4064)
			(stroke
				(width 0.1524)
				(type default)
			)
			(layer "F.SilkS")
		)
		(fp_line
			(start -0.7874 0.4064)
			(end -0.7874 -0.4064)
			(stroke
				(width 0.1524)
				(type default)
			)
			(layer "F.SilkS")
		)
		(fp_line
			(start 0.7874 -0.4064)
			(end 0.7874 0.4064)
			(stroke
				(width 0.1524)
				(type default)
			)
			(layer "F.SilkS")
		)
		(fp_line
			(start 0.7874 0.4064)
			(end -0.7874 0.4064)
			(stroke
				(width 0.1524)
				(type default)
			)
			(layer "F.SilkS")
		)
		(fp_line
			(start -0.67945 -0.305054)
			(end -0.12065 -0.305054)
			(stroke
				(width 0.1)
				(type default)
			)
			(layer "F.Fab")
		)
		(fp_line
			(start -0.67945 0.3048)
			(end -0.67945 -0.305054)
			(stroke
				(width 0.1)
				(type default)
			)
			(layer "F.Fab")
		)
		(fp_line
			(start -0.12065 -0.305054)
			(end -0.12065 -0.2794)
			(stroke
				(width 0.1)
				(type default)
			)
			(layer "F.Fab")
		)
		(fp_line
			(start -0.12065 -0.2794)
			(end 0.12065 -0.2794)
			(stroke
				(width 0.1)
				(type default)
			)
			(layer "F.Fab")
		)
		(fp_line
			(start -0.12065 0.2794)
			(end -0.12065 0.3048)
			(stroke
				(width 0.1)
				(type default)
			)
			(layer "F.Fab")
		)
		(fp_line
			(start -0.12065 0.3048)
			(end -0.67945 0.3048)
			(stroke
				(width 0.1)
				(type default)
			)
			(layer "F.Fab")
		)
		(fp_line
			(start 0.120396 0.2794)
			(end -0.12065 0.2794)
			(stroke
				(width 0.1)
				(type default)
			)
			(layer "F.Fab")
		)
		(fp_line
			(start 0.120396 0.3048)
			(end 0.120396 0.2794)
			(stroke
				(width 0.1)
				(type default)
			)
			(layer "F.Fab")
		)
		(fp_line
			(start 0.12065 -0.3048)
			(end 0.67945 -0.3048)
			(stroke
				(width 0.1)
				(type default)
			)
			(layer "F.Fab")
		)
		(fp_line
			(start 0.12065 -0.2794)
			(end 0.12065 -0.3048)
			(stroke
				(width 0.1)
				(type default)
			)
			(layer "F.Fab")
		)
		(fp_line
			(start 0.67945 -0.3048)
			(end 0.67945 0.3048)
			(stroke
				(width 0.1)
				(type default)
			)
			(layer "F.Fab")
		)
		(fp_line
			(start 0.67945 0.3048)
			(end 0.120396 0.3048)
			(stroke
				(width 0.1)
				(type default)
			)
			(layer "F.Fab")
		)
		(pad "1" smd circle
			(at -0.40005 0)
			(size 0 0)
			(layers "F.Cu" "F.Mask" "F.Paste")
			(net "JTAG_TRST_N")
		)
		(pad "2" smd circle
			(at 0.40005 0)
			(size 0 0)
			(layers "F.Cu" "F.Mask" "F.Paste")
			(net "GND")
		)
	)
)
